(kicad_pcb
	(version 20240108)
	(generator "pcbnew")
	(generator_version "8.0")
	(general
		(thickness 1.586)
		(legacy_teardrops no)
	)
	(paper "A4")
	(title_block
		(title "GMSL Serializer")
		(date "2024-11-27")
		(rev "1.1.1")
		(company "Antmicro Ltd")
		(comment 1 "www.antmicro.com")
		(comment 9 "footprints 54-58 of 117")
	)
	(layers
		(0 "F.Cu" signal)
		(1 "In1.Cu" power)
		(2 "In2.Cu" power)
		(31 "B.Cu" signal)
		(32 "B.Adhes" user "B.Adhesive")
		(33 "F.Adhes" user "F.Adhesive")
		(34 "B.Paste" user)
		(35 "F.Paste" user)
		(36 "B.SilkS" user "B.Silkscreen")
		(37 "F.SilkS" user "F.Silkscreen")
		(38 "B.Mask" user)
		(39 "F.Mask" user)
		(40 "Dwgs.User" user "User.Drawings")
		(41 "Cmts.User" user "User.Comments")
		(42 "Eco1.User" user "User.Eco1")
		(43 "Eco2.User" user "User.Eco2")
		(44 "Edge.Cuts" user)
		(45 "Margin" user)
		(46 "B.CrtYd" user "B.Courtyard")
		(47 "F.CrtYd" user "F.Courtyard")
		(48 "B.Fab" user)
		(49 "F.Fab" user)
	)
	(footprint "antmicro-footprints:DFN-10_2.5x1mm"
		(layer "F.Cu")
		(at 130.5 109.349)
		(property "Reference" "D1"
			(at -0.7 2.351 0)
			(layer "F.SilkS")
			(effects
				(font
					(size 0.7 0.7)
					(thickness 0.15)
				)
				(justify left bottom)
			)
		)
		(property "Value" "PESD4USB5U-TTS"
			(at 2.032 1.524 0)
			(layer "F.Fab")
			(effects
				(font
					(size 0.7 0.7)
					(thickness 0.15)
				)
				(justify left bottom)
			)
		)
		(property "Footprint" "antmicro-footprints:DFN-10_2.5x1mm"
			(at 0 0 0)
			(layer "F.Fab")
			(hide yes)
			(effects
				(font
					(size 1.27 1.27)
					(thickness 0.15)
				)
			)
		)
		(property "Datasheet" "https://assets.nexperia.com/documents/data-sheet/PESD4USB5U-TTS.pdf"
			(at 0 0 0)
			(layer "F.Fab")
			(hide yes)
			(effects
				(font
					(size 1.27 1.27)
					(thickness 0.15)
				)
			)
		)
		(property "Author" "Antmicro"
			(at 0 0 0)
			(layer "F.Fab")
			(hide yes)
			(effects
				(font
					(size 1 1)
					(thickness 0.15)
				)
			)
		)
		(property "License" "Apache-2.0"
			(at 0 0 0)
			(layer "F.Fab")
			(hide yes)
			(effects
				(font
					(size 1 1)
					(thickness 0.15)
				)
			)
		)
		(property "MPN" "PESD4USB5U-TTS"
			(at 0 0 0)
			(layer "F.Fab")
			(hide yes)
			(effects
				(font
					(size 1 1)
					(thickness 0.15)
				)
			)
		)
		(property "Manufacturer" "Nexperia"
			(at 0 0 0)
			(layer "F.Fab")
			(hide yes)
			(effects
				(font
					(size 1 1)
					(thickness 0.15)
				)
			)
		)
		(sheetname "CSI Connector")
		(sheetfile "CSI.kicad_sch")
		(attr smd)
		(fp_line
			(start -0.4 1.4)
			(end 0.4 1.4)
			(stroke
				(width 0.15)
				(type solid)
			)
			(layer "F.SilkS")
		)
		(fp_line
			(start 0.4 -1.4)
			(end -0.4 -1.4)
			(stroke
				(width 0.15)
				(type solid)
			)
			(layer "F.SilkS")
		)
		(fp_circle
			(center -0.762 -1.27)
			(end -0.712 -1.27)
			(stroke
				(width 0.15)
				(type solid)
			)
			(fill solid)
			(layer "F.SilkS")
		)
		(fp_rect
			(start -0.85 -1.6)
			(end 0.85 1.6)
			(stroke
				(width 0.05)
				(type solid)
			)
			(fill none)
			(layer "F.CrtYd")
		)
		(fp_line
			(start -0.5 -0.9)
			(end -0.5 1.25)
			(stroke
				(width 0.15)
				(type solid)
			)
			(layer "F.Fab")
		)
		(fp_line
			(start -0.5 1.25)
			(end 0.5 1.25)
			(stroke
				(width 0.15)
				(type solid)
			)
			(layer "F.Fab")
		)
		(fp_line
			(start -0.15 -1.25)
			(end -0.5 -0.9)
			(stroke
				(width 0.15)
				(type solid)
			)
			(layer "F.Fab")
		)
		(fp_line
			(start 0.5 -1.25)
			(end -0.15 -1.25)
			(stroke
				(width 0.15)
				(type solid)
			)
			(layer "F.Fab")
		)
		(fp_line
			(start 0.5 1.25)
			(end 0.5 -1.25)
			(stroke
				(width 0.15)
				(type solid)
			)
			(layer "F.Fab")
		)
		(fp_text user "License: Apache-2.0"
			(at -0.95 5.924 0)
			(layer "F.Fab")
			(hide yes)
			(effects
				(font
					(size 0.7 0.7)
					(thickness 0.15)
				)
				(justify left bottom)
			)
		)
		(fp_text user "Author: Antmicro"
			(at -0.95 4.724 0)
			(layer "F.Fab")
			(hide yes)
			(effects
				(font
					(size 0.7 0.7)
					(thickness 0.15)
				)
				(justify left bottom)
			)
		)
		(fp_text user "${REFERENCE}"
			(at -0.95 3.524 0)
			(layer "F.Fab")
			(hide yes)
			(effects
				(font
					(size 0.7 0.7)
					(thickness 0.15)
				)
				(justify left bottom)
			)
		)
		(pad "1" smd roundrect
			(at -0.425 -1 270)
			(size 0.2 0.6)
			(layers "F.Cu" "F.Paste" "F.Mask")
			(roundrect_rratio 0.25)
			(net 34 "/CSI Connector/SDA_CAM0")
			(pinfunction "1")
			(pintype "passive")
			(solder_mask_margin 0.05)
		)
		(pad "2" smd roundrect
			(at -0.425 -0.5 270)
			(size 0.2 0.6)
			(layers "F.Cu" "F.Paste" "F.Mask")
			(roundrect_rratio 0.25)
			(net 35 "/CSI Connector/SCL_CAM0")
			(pinfunction "2")
			(pintype "passive")
			(solder_mask_margin 0.05)
		)
		(pad "3" smd roundrect
			(at -0.425 0 270)
			(size 0.4 0.6)
			(layers "F.Cu" "F.Paste" "F.Mask")
			(roundrect_rratio 0.25)
			(net 1 "GND")
			(pinfunction "3")
			(pintype "passive")
			(solder_mask_margin 0.05)
		)
		(pad "4" smd roundrect
			(at -0.425 0.5 270)
			(size 0.2 0.6)
			(layers "F.Cu" "F.Paste" "F.Mask")
			(roundrect_rratio 0.25)
			(net 36 "/CSI Connector/SDA_CAM1")
			(pinfunction "4")
			(pintype "passive")
			(solder_mask_margin 0.05)
		)
		(pad "5" smd roundrect
			(at -0.425 1 270)
			(size 0.2 0.6)
			(layers "F.Cu" "F.Paste" "F.Mask")
			(roundrect_rratio 0.25)
			(net 37 "/CSI Connector/SCL_CAM1")
			(pinfunction "5")
			(pintype "passive")
			(solder_mask_margin 0.05)
		)
		(pad "6" smd roundrect
			(at 0.425 1 270)
			(size 0.2 0.6)
			(layers "F.Cu" "F.Paste" "F.Mask")
			(roundrect_rratio 0.25)
			(net 37 "/CSI Connector/SCL_CAM1")
			(pinfunction "6")
			(pintype "passive")
			(solder_mask_margin 0.05)
		)
		(pad "7" smd roundrect
			(at 0.425 0.5 270)
			(size 0.2 0.6)
			(layers "F.Cu" "F.Paste" "F.Mask")
			(roundrect_rratio 0.25)
			(net 36 "/CSI Connector/SDA_CAM1")
			(pinfunction "7")
			(pintype "passive")
			(solder_mask_margin 0.05)
		)
		(pad "8" smd roundrect
			(at 0.425 0 270)
			(size 0.4 0.6)
			(layers "F.Cu" "F.Paste" "F.Mask")
			(roundrect_rratio 0.25)
			(net 1 "GND")
			(pinfunction "8")
			(pintype "passive")
			(solder_mask_margin 0.05)
		)
		(pad "9" smd roundrect
			(at 0.425 -0.5 270)
			(size 0.2 0.6)
			(layers "F.Cu" "F.Paste" "F.Mask")
			(roundrect_rratio 0.25)
			(net 35 "/CSI Connector/SCL_CAM0")
			(pinfunction "9")
			(pintype "passive")
			(solder_mask_margin 0.05)
		)
		(pad "10" smd roundrect
			(at 0.425 -1 270)
			(size 0.2 0.6)
			(layers "F.Cu" "F.Paste" "F.Mask")
			(roundrect_rratio 0.25)
			(net 34 "/CSI Connector/SDA_CAM0")
			(pinfunction "10")
			(pintype "passive")
			(solder_mask_margin 0.05)
		)
	)
	(footprint "antmicro-footprints:R_0402_1005Metric"
		(layer "F.Cu")
		(at 163.95 98.125)
		(descr "Resistor SMD 0402")
		(tags "resistor SMD 0402")
		(property "Reference" "R8"
			(at -0.65 1.275 0)
			(layer "F.SilkS")
			(effects
				(font
					(size 0.7 0.7)
					(thickness 0.15)
				)
				(justify left bottom)
			)
		)
		(property "Value" "R_10k_0402"
			(at -1.011843 1.772047 0)
			(layer "F.Fab")
			(effects
				(font
					(size 0.7 0.7)
					(thickness 0.15)
				)
				(justify left bottom)
			)
		)
		(property "Footprint" "antmicro-footprints:R_0402_1005Metric"
			(at 0 0 0)
			(layer "F.Fab")
			(hide yes)
			(effects
				(font
					(size 1.27 1.27)
					(thickness 0.15)
				)
			)
		)
		(property "Datasheet" "https://www.bourns.com/docs/product-datasheets/cr.pdf"
			(at 0 0 0)
			(layer "F.Fab")
			(hide yes)
			(effects
				(font
					(size 1.27 1.27)
					(thickness 0.15)
				)
			)
		)
		(property "Author" "Antmicro"
			(at 0 0 0)
			(layer "F.Fab")
			(hide yes)
			(effects
				(font
					(size 1 1)
					(thickness 0.15)
				)
			)
		)
		(property "License" "Apache-2.0"
			(at 0 0 0)
			(layer "F.Fab")
			(hide yes)
			(effects
				(font
					(size 1 1)
					(thickness 0.15)
				)
			)
		)
		(property "MPN" "CR0402-FX-1002GLF"
			(at 0 0 0)
			(layer "F.Fab")
			(hide yes)
			(effects
				(font
					(size 1 1)
					(thickness 0.15)
				)
			)
		)
		(property "Manufacturer" "Bourns"
			(at 0 0 0)
			(layer "F.Fab")
			(hide yes)
			(effects
				(font
					(size 1 1)
					(thickness 0.15)
				)
			)
		)
		(property "Tolerance" "1%"
			(at 0 0 0)
			(layer "F.Fab")
			(hide yes)
			(effects
				(font
					(size 1 1)
					(thickness 0.15)
				)
			)
		)
		(property "Val" "10k"
			(at 0 0 0)
			(layer "F.Fab")
			(hide yes)
			(effects
				(font
					(size 1 1)
					(thickness 0.15)
				)
			)
		)
		(sheetname "Supply")
		(sheetfile "supply.kicad_sch")
		(attr smd)
		(fp_rect
			(start -0.925 -0.47)
			(end 0.925 0.47)
			(stroke
				(width 0.05)
				(type default)
			)
			(fill none)
			(layer "F.CrtYd")
		)
		(fp_rect
			(start -0.5 -0.25)
			(end 0.5 0.25)
			(stroke
				(width 0.15)
				(type solid)
			)
			(fill none)
			(layer "F.Fab")
		)
		(fp_text user "${REFERENCE}"
			(at -0.95 3.168 0)
			(layer "F.Fab")
			(hide yes)
			(effects
				(font
					(size 0.7 0.7)
					(thickness 0.15)
				)
				(justify left bottom)
			)
		)
		(fp_text user "License: Apache-2.0"
			(at -0.95 5.169 0)
			(layer "F.Fab")
			(hide yes)
			(effects
				(font
					(size 0.7 0.7)
					(thickness 0.15)
				)
				(justify left bottom)
			)
		)
		(fp_text user "Author: Antmicro"
			(at -0.95 4.169 0)
			(layer "F.Fab")
			(hide yes)
			(effects
				(font
					(size 0.7 0.7)
					(thickness 0.15)
				)
				(justify left bottom)
			)
		)
		(pad "1" smd roundrect
			(at -0.48 0)
			(size 0.59 0.64)
			(layers "F.Cu" "F.Paste" "F.Mask")
			(roundrect_rratio 0.25)
			(net 63 "/Supply/EN_1V8")
			(pintype "passive")
		)
		(pad "2" smd roundrect
			(at 0.48 0)
			(size 0.59 0.64)
			(layers "F.Cu" "F.Paste" "F.Mask")
			(roundrect_rratio 0.25)
			(net 2 "+12V")
			(pintype "passive")
		)
	)
	(footprint "antmicro-footprints:R_0402_1005Metric"
		(layer "F.Cu")
		(at 135.4 107.7)
		(descr "Resistor SMD 0402")
		(tags "resistor SMD 0402")
		(property "Reference" "R32"
			(at 0.9 0.4 0)
			(layer "F.SilkS")
			(effects
				(font
					(size 0.7 0.7)
					(thickness 0.15)
				)
				(justify left bottom)
			)
		)
		(property "Value" "R_0R_0402"
			(at -1.011843 1.772047 0)
			(layer "F.Fab")
			(effects
				(font
					(size 0.7 0.7)
					(thickness 0.15)
				)
				(justify left bottom)
			)
		)
		(property "Footprint" "antmicro-footprints:R_0402_1005Metric"
			(at 0 0 0)
			(layer "F.Fab")
			(hide yes)
			(effects
				(font
					(size 1.27 1.27)
					(thickness 0.15)
				)
			)
		)
		(property "Datasheet" "https://industrial.panasonic.com/cdbs/www-data/pdf/RDA0000/AOA0000C301.pdf"
			(at 0 0 0)
			(layer "F.Fab")
			(hide yes)
			(effects
				(font
					(size 1.27 1.27)
					(thickness 0.15)
				)
			)
		)
		(property "Author" "Antmicro"
			(at 0 0 0)
			(layer "F.Fab")
			(hide yes)
			(effects
				(font
					(size 1 1)
					(thickness 0.15)
				)
			)
		)
		(property "Current" "1A"
			(at 0 0 0)
			(layer "F.Fab")
			(hide yes)
			(effects
				(font
					(size 1 1)
					(thickness 0.15)
				)
			)
		)
		(property "License" "Apache-2.0"
			(at 0 0 0)
			(layer "F.Fab")
			(hide yes)
			(effects
				(font
					(size 1 1)
					(thickness 0.15)
				)
			)
		)
		(property "MPN" "ERJ2GE0R00X"
			(at 0 0 0)
			(layer "F.Fab")
			(hide yes)
			(effects
				(font
					(size 1 1)
					(thickness 0.15)
				)
			)
		)
		(property "Manufacturer" "Panasonic"
			(at 0 0 0)
			(layer "F.Fab")
			(hide yes)
			(effects
				(font
					(size 1 1)
					(thickness 0.15)
				)
			)
		)
		(property "Tolerance" ""
			(at 0 0 0)
			(layer "F.Fab")
			(hide yes)
			(effects
				(font
					(size 1 1)
					(thickness 0.15)
				)
			)
		)
		(property "Val" "0R"
			(at 0 0 0)
			(layer "F.Fab")
			(hide yes)
			(effects
				(font
					(size 1 1)
					(thickness 0.15)
				)
			)
		)
		(sheetname "Serializer")
		(sheetfile "serializer.kicad_sch")
		(attr smd)
		(fp_rect
			(start -0.925 -0.47)
			(end 0.925 0.47)
			(stroke
				(width 0.05)
				(type default)
			)
			(fill none)
			(layer "F.CrtYd")
		)
		(fp_rect
			(start -0.5 -0.25)
			(end 0.5 0.25)
			(stroke
				(width 0.15)
				(type solid)
			)
			(fill none)
			(layer "F.Fab")
		)
		(fp_text user "${REFERENCE}"
			(at -0.95 3.168 0)
			(layer "F.Fab")
			(hide yes)
			(effects
				(font
					(size 0.7 0.7)
					(thickness 0.15)
				)
				(justify left bottom)
			)
		)
		(fp_text user "Author: Antmicro"
			(at -0.95 4.169 0)
			(layer "F.Fab")
			(hide yes)
			(effects
				(font
					(size 0.7 0.7)
					(thickness 0.15)
				)
				(justify left bottom)
			)
		)
		(fp_text user "License: Apache-2.0"
			(at -0.95 5.169 0)
			(layer "F.Fab")
			(hide yes)
			(effects
				(font
					(size 0.7 0.7)
					(thickness 0.15)
				)
				(justify left bottom)
			)
		)
		(pad "1" smd roundrect
			(at -0.48 0)
			(size 0.59 0.64)
			(layers "F.Cu" "F.Paste" "F.Mask")
			(roundrect_rratio 0.25)
			(net 88 "/CSI Connector/I2C.SDA")
			(pintype "passive")
		)
		(pad "2" smd roundrect
			(at 0.48 0)
			(size 0.59 0.64)
			(layers "F.Cu" "F.Paste" "F.Mask")
			(roundrect_rratio 0.25)
			(net 81 "Net-(U6-MFP9)")
			(pintype "passive")
		)
	)
	(footprint "antmicro-footprints:C_0402_1005Metric"
		(layer "F.Cu")
		(at 137.78 85.647 -90)
		(descr "Capacitor SMD 0402")
		(tags "capacitor SMD 0402")
		(property "Reference" "C5"
			(at 0.773 -1.469 90)
			(layer "F.SilkS")
			(effects
				(font
					(size 0.7 0.7)
					(thickness 0.15)
				)
				(justify right bottom)
			)
		)
		(property "Value" "C_22u_0402"
			(at -1.022927 2.155213 90)
			(layer "F.Fab")
			(effects
				(font
					(size 0.7 0.7)
					(thickness 0.15)
				)
				(justify right bottom)
			)
		)
		(property "Footprint" "antmicro-footprints:C_0402_1005Metric"
			(at 0 0 -90)
			(layer "F.Fab")
			(hide yes)
			(effects
				(font
					(size 1.27 1.27)
					(thickness 0.15)
				)
			)
		)
		(property "Datasheet" "https://www.murata.com/products/productdetail?partno=GRM158R60J226ME01%23"
			(at 0 0 -90)
			(layer "F.Fab")
			(hide yes)
			(effects
				(font
					(size 1.27 1.27)
					(thickness 0.15)
				)
			)
		)
		(property "Author" "Antmicro"
			(at 54.053 225.047 0)
			(layer "F.Fab")
			(hide yes)
			(effects
				(font
					(size 1 1)
					(thickness 0.15)
				)
			)
		)
		(property "Dielectric" ""
			(at 54.053 225.047 0)
			(layer "F.Fab")
			(hide yes)
			(effects
				(font
					(size 1 1)
					(thickness 0.15)
				)
			)
		)
		(property "License" "Apache-2.0"
			(at 54.053 225.047 0)
			(layer "F.Fab")
			(hide yes)
			(effects
				(font
					(size 1 1)
					(thickness 0.15)
				)
			)
		)
		(property "MPN" "GRM158R60J226ME01D"
			(at 54.053 225.047 0)
			(layer "F.Fab")
			(hide yes)
			(effects
				(font
					(size 1 1)
					(thickness 0.15)
				)
			)
		)
		(property "Manufacturer" "Murata"
			(at 54.053 225.047 0)
			(layer "F.Fab")
			(hide yes)
			(effects
				(font
					(size 1 1)
					(thickness 0.15)
				)
			)
		)
		(property "Val" "22u"
			(at 54.053 225.047 0)
			(layer "F.Fab")
			(hide yes)
			(effects
				(font
					(size 1 1)
					(thickness 0.15)
				)
			)
		)
		(property "Voltage" ""
			(at 54.053 225.047 0)
			(layer "F.Fab")
			(hide yes)
			(effects
				(font
					(size 1 1)
					(thickness 0.15)
				)
			)
		)
		(sheetname "Supply")
		(sheetfile "supply.kicad_sch")
		(attr smd)
		(fp_rect
			(start -0.925 -0.47)
			(end 0.925 0.47)
			(stroke
				(width 0.05)
				(type default)
			)
			(fill none)
			(layer "F.CrtYd")
		)
		(fp_line
			(start -0.494 0.248)
			(end -0.494 -0.25)
			(stroke
				(width 0.15)
				(type solid)
			)
			(layer "F.Fab")
		)
		(fp_line
			(start 0.504 0.248)
			(end -0.494 0.248)
			(stroke
				(width 0.15)
				(type solid)
			)
			(layer "F.Fab")
		)
		(fp_line
			(start -0.494 -0.25)
			(end 0.504 -0.25)
			(stroke
				(width 0.15)
				(type solid)
			)
			(layer "F.Fab")
		)
		(fp_line
			(start 0.504 -0.25)
			(end 0.504 0.248)
			(stroke
				(width 0.15)
				(type solid)
			)
			(layer "F.Fab")
		)
		(fp_text user "License: Apache-2.0"
			(at -0.939 5.799 90)
			(layer "F.Fab")
			(hide yes)
			(effects
				(font
					(size 0.7 0.7)
					(thickness 0.15)
				)
				(justify right bottom)
			)
		)
		(fp_text user "Author: Antmicro"
			(at -0.939 3.399 90)
			(layer "F.Fab")
			(hide yes)
			(effects
				(font
					(size 0.7 0.7)
					(thickness 0.15)
				)
				(justify right bottom)
			)
		)
		(fp_text user "${REFERENCE}"
			(at -0.939 4.599 90)
			(layer "F.Fab")
			(hide yes)
			(effects
				(font
					(size 0.7 0.7)
					(thickness 0.15)
				)
				(justify right bottom)
			)
		)
		(pad "1" smd roundrect
			(at -0.48 0 270)
			(size 0.59 0.64)
			(layers "F.Cu" "F.Paste" "F.Mask")
			(roundrect_rratio 0.25)
			(net 1 "GND")
			(pintype "passive")
		)
		(pad "2" smd roundrect
			(at 0.48 0 270)
			(size 0.59 0.64)
			(layers "F.Cu" "F.Paste" "F.Mask")
			(roundrect_rratio 0.25)
			(net 7 "/Supply/OUT_5V")
			(pintype "passive")
		)
	)
	(footprint "antmicro-footprints:R_0402_1005Metric"
		(layer "F.Cu")
		(at 160.986 97.8 180)
		(descr "Resistor SMD 0402")
		(tags "resistor SMD 0402")
		(property "Reference" "R12"
			(at 0.886 -1.3 0)
			(layer "F.SilkS")
			(effects
				(font
					(size 0.7 0.7)
					(thickness 0.15)
				)
				(justify right bottom)
			)
		)
		(property "Value" "R_10k_0402"
			(at -1.011843 1.772047 0)
			(layer "F.Fab")
			(effects
				(font
					(size 0.7 0.7)
					(thickness 0.15)
				)
				(justify right bottom)
			)
		)
		(property "Footprint" "antmicro-footprints:R_0402_1005Metric"
			(at 0 0 180)
			(layer "F.Fab")
			(hide yes)
			(effects
				(font
					(size 1.27 1.27)
					(thickness 0.15)
				)
			)
		)
		(property "Datasheet" "https://www.bourns.com/docs/product-datasheets/cr.pdf"
			(at 0 0 180)
			(layer "F.Fab")
			(hide yes)
			(effects
				(font
					(size 1.27 1.27)
					(thickness 0.15)
				)
			)
		)
		(property "Author" "Antmicro"
			(at 321.972 195.6 0)
			(layer "F.Fab")
			(hide yes)
			(effects
				(font
					(size 1 1)
					(thickness 0.15)
				)
			)
		)
		(property "License" "Apache-2.0"
			(at 321.972 195.6 0)
			(layer "F.Fab")
			(hide yes)
			(effects
				(font
					(size 1 1)
					(thickness 0.15)
				)
			)
		)
		(property "MPN" "CR0402-FX-1002GLF"
			(at 321.972 195.6 0)
			(layer "F.Fab")
			(hide yes)
			(effects
				(font
					(size 1 1)
					(thickness 0.15)
				)
			)
		)
		(property "Manufacturer" "Bourns"
			(at 321.972 195.6 0)
			(layer "F.Fab")
			(hide yes)
			(effects
				(font
					(size 1 1)
					(thickness 0.15)
				)
			)
		)
		(property "Tolerance" "1%"
			(at 321.972 195.6 0)
			(layer "F.Fab")
			(hide yes)
			(effects
				(font
					(size 1 1)
					(thickness 0.15)
				)
			)
		)
		(property "Val" "10k"
			(at 321.972 195.6 0)
			(layer "F.Fab")
			(hide yes)
			(effects
				(font
					(size 1 1)
					(thickness 0.15)
				)
			)
		)
		(sheetname "Supply")
		(sheetfile "supply.kicad_sch")
		(attr smd)
		(fp_rect
			(start -0.925 -0.47)
			(end 0.925 0.47)
			(stroke
				(width 0.05)
				(type default)
			)
			(fill none)
			(layer "F.CrtYd")
		)
		(fp_rect
			(start -0.5 -0.25)
			(end 0.5 0.25)
			(stroke
				(width 0.15)
				(type solid)
			)
			(fill none)
			(layer "F.Fab")
		)
		(fp_text user "License: Apache-2.0"
			(at -0.95 5.169 0)
			(layer "F.Fab")
			(hide yes)
			(effects
				(font
					(size 0.7 0.7)
					(thickness 0.15)
				)
				(justify right bottom)
			)
		)
		(fp_text user "${REFERENCE}"
			(at -0.95 3.168 0)
			(layer "F.Fab")
			(hide yes)
			(effects
				(font
					(size 0.7 0.7)
					(thickness 0.15)
				)
				(justify right bottom)
			)
		)
		(fp_text user "Author: Antmicro"
			(at -0.95 4.169 0)
			(layer "F.Fab")
			(hide yes)
			(effects
				(font
					(size 0.7 0.7)
					(thickness 0.15)
				)
				(justify right bottom)
			)
		)
		(pad "1" smd roundrect
			(at -0.48 0 180)
			(size 0.59 0.64)
			(layers "F.Cu" "F.Paste" "F.Mask")
			(roundrect_rratio 0.25)
			(net 1 "GND")
			(pintype "passive")
		)
		(pad "2" smd roundrect
			(at 0.48 0 180)
			(size 0.59 0.64)
			(layers "F.Cu" "F.Paste" "F.Mask")
			(roundrect_rratio 0.25)
			(net 65 "/Supply/FB_1V8")
			(pintype "passive")
		)
	)
)
